# T6G (Grand Teton) — schematic netlist excerpt (pin names and nets, part order shuffled) for the footprints in the layout excerpt that follows; sources: Cadence DE-HDL packaged netlist, KiCad conversion of 04192023_DAF0TMB3IC0_F0TG_MB_C_brd_V02_OCP.brd

C421  Q_CAP  0.1UF 10V 10% X7S  pkg C0201  page 345 : A = P0V9_CPU1_RT2_2A ; B = GND
C525  Q_CAP  1UF 4V 20% X6S  pkg 0201  page 279 : A = P0V9_CPU0_RT0_2A ; B = GND
C2372  Q_CAP  22UF 4V 20% X6S  pkg C0402  page 73 : A = PVDDCR_CPU1_P1 ; B = GND

(kicad_pcb
	(version 20260206)
	(generator "pcbnew")
	(generator_version "10.0")
	(general
		(thickness 1.6)
		(legacy_teardrops no)
	)
	(paper "A4")
	(title_block
		(title "04192023_DAF0TMB3IC0_F0TG_MB_C_brd_V02_OCP.brd")
		(comment 1 "Grand Teton / footprints 8238-8240 of 8354")
	)
	(layers
		(0 "F.Cu" signal "TOP")
		(4 "In1.Cu" signal "GND")
		(6 "In2.Cu" signal "IN1")
		(8 "In3.Cu" signal "GND1")
		(10 "In4.Cu" signal "IN2")
		(12 "In5.Cu" signal "GND2")
		(14 "In6.Cu" signal "IN3")
		(16 "In7.Cu" signal "GND3")
		(18 "In8.Cu" signal "VCC")
		(20 "In9.Cu" signal "VCC1")
		(22 "In10.Cu" signal "GND4")
		(24 "In11.Cu" signal "IN4")
		(26 "In12.Cu" signal "GND5")
		(28 "In13.Cu" signal "IN5")
		(30 "In14.Cu" signal "GND6")
		(32 "In15.Cu" signal "IN6")
		(34 "In16.Cu" signal "GND7")
		(2 "B.Cu" signal "BOTTOM")
		(9 "F.Adhes" user "F.Adhesive")
		(11 "B.Adhes" user "B.Adhesive")
		(13 "F.Paste" user "Package Geometry/Pastemask Top")
		(15 "B.Paste" user "Package Geometry/Pastemask Bottom")
		(5 "F.SilkS" user "Ref Des/Silkscreen Top")
		(7 "B.SilkS" user "Ref Des/Silkscreen Bottom")
		(1 "F.Mask" user "Board Geometry/Soldermask Top")
		(3 "B.Mask" user "Board Geometry/Soldermask Bottom")
		(17 "Dwgs.User" user "User.Drawings")
		(19 "Cmts.User" user "User.Comments")
		(21 "Eco1.User" user "User.Eco1")
		(23 "Eco2.User" user "User.Eco2")
		(25 "Edge.Cuts" user "Board Geometry/Outline")
		(27 "Margin" user)
		(31 "F.CrtYd" user "Package Geometry/Place Bound Top")
		(29 "B.CrtYd" user "Package Geometry/Place Bound Bottom")
		(35 "F.Fab" user "Ref Des/Assembly Top")
		(33 "B.Fab" user "Ref Des/Assembly Bottom")
	)
	(footprint ""
		(layer "B.Cu")
		(at 122.496834 -272.284952)
		(property "Reference" "C2372"
			(at 0 0 0)
			(layer "B.SilkS")
			(hide yes)
			(effects
				(font
					(size 1.27 1.27)
				)
				(justify mirror)
			)
		)
		(property "Value" ""
			(at 0 0 0)
			(layer "B.Fab")
			(effects
				(font
					(size 1.27 1.27)
				)
				(justify mirror)
			)
		)
		(duplicate_pad_numbers_are_jumpers no)
		(fp_line
			(start -0.7874 -0.4064)
			(end -0.7874 0.4064)
			(stroke
				(width 0.1524)
				(type default)
			)
			(layer "B.SilkS")
		)
		(fp_line
			(start -0.7874 0.4064)
			(end 0.7874 0.4064)
			(stroke
				(width 0.1524)
				(type default)
			)
			(layer "B.SilkS")
		)
		(fp_line
			(start 0.7874 -0.4064)
			(end -0.7874 -0.4064)
			(stroke
				(width 0.1524)
				(type default)
			)
			(layer "B.SilkS")
		)
		(fp_line
			(start 0.7874 0.4064)
			(end 0.7874 -0.4064)
			(stroke
				(width 0.1524)
				(type default)
			)
			(layer "B.SilkS")
		)
		(fp_line
			(start -0.67945 -0.3048)
			(end -0.67945 0.3048)
			(stroke
				(width 0.1)
				(type default)
			)
			(layer "B.Fab")
		)
		(fp_line
			(start -0.67945 0.3048)
			(end -0.120396 0.3048)
			(stroke
				(width 0.1)
				(type default)
			)
			(layer "B.Fab")
		)
		(fp_line
			(start -0.12065 -0.3048)
			(end -0.67945 -0.3048)
			(stroke
				(width 0.1)
				(type default)
			)
			(layer "B.Fab")
		)
		(fp_line
			(start -0.12065 -0.2794)
			(end -0.12065 -0.3048)
			(stroke
				(width 0.1)
				(type default)
			)
			(layer "B.Fab")
		)
		(fp_line
			(start -0.120396 0.2794)
			(end 0.12065 0.2794)
			(stroke
				(width 0.1)
				(type default)
			)
			(layer "B.Fab")
		)
		(fp_line
			(start -0.120396 0.3048)
			(end -0.120396 0.2794)
			(stroke
				(width 0.1)
				(type default)
			)
			(layer "B.Fab")
		)
		(fp_line
			(start 0.12065 -0.305054)
			(end 0.12065 -0.2794)
			(stroke
				(width 0.1)
				(type default)
			)
			(layer "B.Fab")
		)
		(fp_line
			(start 0.12065 -0.2794)
			(end -0.12065 -0.2794)
			(stroke
				(width 0.1)
				(type default)
			)
			(layer "B.Fab")
		)
		(fp_line
			(start 0.12065 0.2794)
			(end 0.12065 0.3048)
			(stroke
				(width 0.1)
				(type default)
			)
			(layer "B.Fab")
		)
		(fp_line
			(start 0.12065 0.3048)
			(end 0.67945 0.3048)
			(stroke
				(width 0.1)
				(type default)
			)
			(layer "B.Fab")
		)
		(fp_line
			(start 0.67945 -0.305054)
			(end 0.12065 -0.305054)
			(stroke
				(width 0.1)
				(type default)
			)
			(layer "B.Fab")
		)
		(fp_line
			(start 0.67945 0.3048)
			(end 0.67945 -0.305054)
			(stroke
				(width 0.1)
				(type default)
			)
			(layer "B.Fab")
		)
		(pad "1" smd circle
			(at 0.40005 0 180)
			(size 0 0)
			(layers "B.Cu" "B.Mask" "B.Paste")
			(net "PVDDCR_CPU1_P1")
		)
		(pad "2" smd circle
			(at -0.40005 0 180)
			(size 0 0)
			(layers "B.Cu" "B.Mask" "B.Paste")
			(net "GND")
		)
	)
	(footprint ""
		(layer "B.Cu")
		(at 321.378326 -395.148562 90)
		(property "Reference" "C525"
			(at 0 0 90)
			(layer "B.SilkS")
			(hide yes)
			(effects
				(font
					(size 1.27 1.27)
				)
				(justify mirror)
			)
		)
		(property "Value" ""
			(at 0 0 90)
			(layer "B.Fab")
			(effects
				(font
					(size 1.27 1.27)
				)
				(justify mirror)
			)
		)
		(duplicate_pad_numbers_are_jumpers no)
		(fp_line
			(start 0.299974 -0.150114)
			(end -0.299974 -0.150114)
			(stroke
				(width 0.1)
				(type default)
			)
			(layer "B.Fab")
		)
		(fp_line
			(start -0.299974 -0.150114)
			(end -0.299974 0.150114)
			(stroke
				(width 0.1)
				(type default)
			)
			(layer "B.Fab")
		)
		(fp_line
			(start 0.299974 0.150114)
			(end 0.299974 -0.150114)
			(stroke
				(width 0.1)
				(type default)
			)
			(layer "B.Fab")
		)
		(fp_line
			(start -0.299974 0.150114)
			(end 0.299974 0.150114)
			(stroke
				(width 0.1)
				(type default)
			)
			(layer "B.Fab")
		)
		(pad "1" smd rect
			(at 0.2667 0 270)
			(size 0.3048 0.381)
			(layers "B.Cu" "B.Mask" "B.Paste")
			(net "P0V9_CPU0_RT0_2A")
		)
		(pad "2" smd rect
			(at -0.2667 0 270)
			(size 0.3048 0.381)
			(layers "B.Cu" "B.Mask" "B.Paste")
			(net "GND")
		)
	)
	(footprint ""
		(layer "B.Cu")
		(at 147.146264 -388.011162 -90)
		(property "Reference" "C421"
			(at 0 0 90)
			(layer "B.SilkS")
			(hide yes)
			(effects
				(font
					(size 1.27 1.27)
				)
				(justify mirror)
			)
		)
		(property "Value" ""
			(at 0 0 90)
			(layer "B.Fab")
			(effects
				(font
					(size 1.27 1.27)
				)
				(justify mirror)
			)
		)
		(duplicate_pad_numbers_are_jumpers no)
		(fp_line
			(start -0.299974 0.150114)
			(end 0.299974 0.150114)
			(stroke
				(width 0.1)
				(type default)
			)
			(layer "B.Fab")
		)
		(fp_line
			(start 0.299974 0.150114)
			(end 0.299974 -0.150114)
			(stroke
				(width 0.1)
				(type default)
			)
			(layer "B.Fab")
		)
		(fp_line
			(start -0.299974 -0.150114)
			(end -0.299974 0.150114)
			(stroke
				(width 0.1)
				(type default)
			)
			(layer "B.Fab")
		)
		(fp_line
			(start 0.299974 -0.150114)
			(end -0.299974 -0.150114)
			(stroke
				(width 0.1)
				(type default)
			)
			(layer "B.Fab")
		)
		(pad "1" smd rect
			(at 0.2667 0 90)
			(size 0.3048 0.381)
			(layers "B.Cu" "B.Mask" "B.Paste")
			(net "P0V9_CPU1_RT2_2A")
		)
		(pad "2" smd rect
			(at -0.2667 0 90)
			(size 0.3048 0.381)
			(layers "B.Cu" "B.Mask" "B.Paste")
			(net "GND")
		)
	)
)
